(kicad_pcb
	(version 20260206)
	(generator "pcbnew")
	(generator_version "10.0")
	(general
		(thickness 1.6)
		(legacy_teardrops no)
	)
	(paper "A4")
	(title_block
		(title "03242023_DA0F0TMBIJ0_F0T_Motherboard_J_brd_V01_OCP.brd")
		(comment 1 "Grand Teton / footprints 3780-3786 of 6105")
	)
	(layers
		(0 "F.Cu" signal "TOP")
		(4 "In1.Cu" signal "GND")
		(6 "In2.Cu" signal "IN1")
		(8 "In3.Cu" signal "GND1")
		(10 "In4.Cu" signal "IN2")
		(12 "In5.Cu" signal "GND2")
		(14 "In6.Cu" signal "IN3")
		(16 "In7.Cu" signal "GND3")
		(18 "In8.Cu" signal "VCC")
		(20 "In9.Cu" signal "VCC1")
		(22 "In10.Cu" signal "GND4")
		(24 "In11.Cu" signal "IN4")
		(26 "In12.Cu" signal "GND5")
		(28 "In13.Cu" signal "IN5")
		(30 "In14.Cu" signal "GND6")
		(32 "In15.Cu" signal "IN6")
		(34 "In16.Cu" signal "GND7")
		(2 "B.Cu" signal "BOTTOM")
		(9 "F.Adhes" user "F.Adhesive")
		(11 "B.Adhes" user "B.Adhesive")
		(13 "F.Paste" user "Package Geometry/Pastemask Top")
		(15 "B.Paste" user "Package Geometry/Pastemask Bottom")
		(5 "F.SilkS" user "Ref Des/Silkscreen Top")
		(7 "B.SilkS" user "Ref Des/Silkscreen Bottom")
		(1 "F.Mask" user "Board Geometry/Soldermask Top")
		(3 "B.Mask" user "Board Geometry/Soldermask Bottom")
		(17 "Dwgs.User" user "User.Drawings")
		(19 "Cmts.User" user "User.Comments")
		(21 "Eco1.User" user "User.Eco1")
		(23 "Eco2.User" user "User.Eco2")
		(25 "Edge.Cuts" user "Board Geometry/Outline")
		(27 "Margin" user)
		(31 "F.CrtYd" user "Package Geometry/Place Bound Top")
		(29 "B.CrtYd" user "Package Geometry/Place Bound Bottom")
		(35 "F.Fab" user "Ref Des/Assembly Top")
		(33 "B.Fab" user "Ref Des/Assembly Bottom")
	)
	(footprint ""
		(layer "F.Cu")
		(at 256.466594 -394.17117)
		(property "Reference" "PR2528"
			(at 0 0 0)
			(layer "F.SilkS")
			(hide yes)
			(effects
				(font
					(size 1.27 1.27)
				)
			)
		)
		(property "Value" ""
			(at 0 0 0)
			(layer "F.Fab")
			(effects
				(font
					(size 1.27 1.27)
				)
			)
		)
		(duplicate_pad_numbers_are_jumpers no)
		(fp_line
			(start -0.7874 -0.4064)
			(end 0.7874 -0.4064)
			(stroke
				(width 0.1524)
				(type default)
			)
			(layer "F.SilkS")
		)
		(fp_line
			(start -0.7874 0.4064)
			(end -0.7874 -0.4064)
			(stroke
				(width 0.1524)
				(type default)
			)
			(layer "F.SilkS")
		)
		(fp_line
			(start 0.7874 -0.4064)
			(end 0.7874 0.4064)
			(stroke
				(width 0.1524)
				(type default)
			)
			(layer "F.SilkS")
		)
		(fp_line
			(start 0.7874 0.4064)
			(end -0.7874 0.4064)
			(stroke
				(width 0.1524)
				(type default)
			)
			(layer "F.SilkS")
		)
		(fp_line
			(start -0.67945 -0.305054)
			(end -0.12065 -0.305054)
			(stroke
				(width 0.1)
				(type default)
			)
			(layer "F.Fab")
		)
		(fp_line
			(start -0.67945 0.3048)
			(end -0.67945 -0.305054)
			(stroke
				(width 0.1)
				(type default)
			)
			(layer "F.Fab")
		)
		(fp_line
			(start -0.12065 -0.305054)
			(end -0.12065 -0.2794)
			(stroke
				(width 0.1)
				(type default)
			)
			(layer "F.Fab")
		)
		(fp_line
			(start -0.12065 -0.2794)
			(end 0.12065 -0.2794)
			(stroke
				(width 0.1)
				(type default)
			)
			(layer "F.Fab")
		)
		(fp_line
			(start -0.12065 0.2794)
			(end -0.12065 0.3048)
			(stroke
				(width 0.1)
				(type default)
			)
			(layer "F.Fab")
		)
		(fp_line
			(start -0.12065 0.3048)
			(end -0.67945 0.3048)
			(stroke
				(width 0.1)
				(type default)
			)
			(layer "F.Fab")
		)
		(fp_line
			(start 0.120396 0.2794)
			(end -0.12065 0.2794)
			(stroke
				(width 0.1)
				(type default)
			)
			(layer "F.Fab")
		)
		(fp_line
			(start 0.120396 0.3048)
			(end 0.120396 0.2794)
			(stroke
				(width 0.1)
				(type default)
			)
			(layer "F.Fab")
		)
		(fp_line
			(start 0.12065 -0.3048)
			(end 0.67945 -0.3048)
			(stroke
				(width 0.1)
				(type default)
			)
			(layer "F.Fab")
		)
		(fp_line
			(start 0.12065 -0.2794)
			(end 0.12065 -0.3048)
			(stroke
				(width 0.1)
				(type default)
			)
			(layer "F.Fab")
		)
		(fp_line
			(start 0.67945 -0.3048)
			(end 0.67945 0.3048)
			(stroke
				(width 0.1)
				(type default)
			)
			(layer "F.Fab")
		)
		(fp_line
			(start 0.67945 0.3048)
			(end 0.120396 0.3048)
			(stroke
				(width 0.1)
				(type default)
			)
			(layer "F.Fab")
		)
		(pad "1" smd circle
			(at -0.40005 0)
			(size 0 0)
			(layers "F.Cu" "F.Mask" "F.Paste")
			(net "P12V_HSC_GATE_G1")
		)
		(pad "2" smd circle
			(at 0.40005 0)
			(size 0 0)
			(layers "F.Cu" "F.Mask" "F.Paste")
			(net "P12V_HSC_GATE2")
		)
	)
	(footprint ""
		(layer "F.Cu")
		(at 380.335536 -105.483152 90)
		(property "Reference" "R2513"
			(at 0 0 90)
			(layer "F.SilkS")
			(hide yes)
			(effects
				(font
					(size 1.27 1.27)
				)
			)
		)
		(property "Value" ""
			(at 0 0 90)
			(layer "F.Fab")
			(effects
				(font
					(size 1.27 1.27)
				)
			)
		)
		(duplicate_pad_numbers_are_jumpers no)
		(fp_line
			(start 0.7874 -0.4064)
			(end 0.7874 0.4064)
			(stroke
				(width 0.1524)
				(type default)
			)
			(layer "F.SilkS")
		)
		(fp_line
			(start -0.7874 -0.4064)
			(end 0.7874 -0.4064)
			(stroke
				(width 0.1524)
				(type default)
			)
			(layer "F.SilkS")
		)
		(fp_line
			(start 0.7874 0.4064)
			(end -0.7874 0.4064)
			(stroke
				(width 0.1524)
				(type default)
			)
			(layer "F.SilkS")
		)
		(fp_line
			(start -0.7874 0.4064)
			(end -0.7874 -0.4064)
			(stroke
				(width 0.1524)
				(type default)
			)
			(layer "F.SilkS")
		)
		(fp_line
			(start -0.12065 -0.305054)
			(end -0.12065 -0.2794)
			(stroke
				(width 0.1)
				(type default)
			)
			(layer "F.Fab")
		)
		(fp_line
			(start -0.67945 -0.305054)
			(end -0.12065 -0.305054)
			(stroke
				(width 0.1)
				(type default)
			)
			(layer "F.Fab")
		)
		(fp_line
			(start 0.67945 -0.3048)
			(end 0.67945 0.3048)
			(stroke
				(width 0.1)
				(type default)
			)
			(layer "F.Fab")
		)
		(fp_line
			(start 0.12065 -0.3048)
			(end 0.67945 -0.3048)
			(stroke
				(width 0.1)
				(type default)
			)
			(layer "F.Fab")
		)
		(fp_line
			(start 0.12065 -0.2794)
			(end 0.12065 -0.3048)
			(stroke
				(width 0.1)
				(type default)
			)
			(layer "F.Fab")
		)
		(fp_line
			(start -0.12065 -0.2794)
			(end 0.12065 -0.2794)
			(stroke
				(width 0.1)
				(type default)
			)
			(layer "F.Fab")
		)
		(fp_line
			(start 0.120396 0.2794)
			(end -0.12065 0.2794)
			(stroke
				(width 0.1)
				(type default)
			)
			(layer "F.Fab")
		)
		(fp_line
			(start -0.12065 0.2794)
			(end -0.12065 0.3048)
			(stroke
				(width 0.1)
				(type default)
			)
			(layer "F.Fab")
		)
		(fp_line
			(start 0.67945 0.3048)
			(end 0.120396 0.3048)
			(stroke
				(width 0.1)
				(type default)
			)
			(layer "F.Fab")
		)
		(fp_line
			(start 0.120396 0.3048)
			(end 0.120396 0.2794)
			(stroke
				(width 0.1)
				(type default)
			)
			(layer "F.Fab")
		)
		(fp_line
			(start -0.12065 0.3048)
			(end -0.67945 0.3048)
			(stroke
				(width 0.1)
				(type default)
			)
			(layer "F.Fab")
		)
		(fp_line
			(start -0.67945 0.3048)
			(end -0.67945 -0.305054)
			(stroke
				(width 0.1)
				(type default)
			)
			(layer "F.Fab")
		)
		(pad "1" smd circle
			(at -0.40005 0 90)
			(size 0 0)
			(layers "F.Cu" "F.Mask" "F.Paste")
			(net "PD_GTL2014_BMC_JTAG_DIR_2")
		)
		(pad "2" smd circle
			(at 0.40005 0 90)
			(size 0 0)
			(layers "F.Cu" "F.Mask" "F.Paste")
			(net "GND")
		)
	)
	(footprint ""
		(layer "F.Cu")
		(at 180.03393 -363.113066 90)
		(property "Reference" "PC1210"
			(at 0 0 90)
			(layer "F.SilkS")
			(hide yes)
			(effects
				(font
					(size 1.27 1.27)
				)
			)
		)
		(property "Value" ""
			(at 0 0 90)
			(layer "F.Fab")
			(effects
				(font
					(size 1.27 1.27)
				)
			)
		)
		(duplicate_pad_numbers_are_jumpers no)
		(fp_line
			(start -3.400044 1.249934)
			(end 3.400044 1.249934)
			(stroke
				(width 0.1524)
				(type default)
			)
			(layer "F.SilkS")
		)
		(fp_circle
			(center 0 1.249934)
			(end 0 4.649978)
			(stroke
				(width 0.1524)
				(type default)
			)
			(fill no)
			(layer "F.SilkS")
		)
		(fp_poly
			(pts
				(arc
					(start -3.400044 1.249934)
					(mid 0 4.649978)
					(end 3.400044 1.249934)
				)
			)
			(stroke
				(width 0)
				(type default)
			)
			(fill yes)
			(layer "F.SilkS")
		)
		(fp_circle
			(center 0 1.249934)
			(end 0 4.649978)
			(stroke
				(width 0.1)
				(type default)
			)
			(fill no)
			(layer "F.Fab")
		)
		(pad "1" thru_hole rect
			(at 0 0 90)
			(size 1.524 1.524)
			(drill 1.016)
			(layers "*.Cu" "*.Mask")
			(remove_unused_layers no)
			(net "SW_P12V_PVCCFA_EHV_FIVRA_CPU1_R")
			(clearance 0)
			(padstack
				(mode front_inner_back)
				(layer "Inner"
					(shape circle)
					(size 1.524 1.524)
					(clearance 0)
				)
				(layer "B.Cu"
					(shape rect)
					(size 1.524 1.524)
					(clearance 0)
				)
			)
		)
		(pad "2" thru_hole circle
			(at 0 2.500122 90)
			(size 1.524 1.524)
			(drill 1.016)
			(layers "*.Cu" "*.Mask")
			(remove_unused_layers no)
			(net "GND")
			(clearance 0)
		)
	)
	(footprint ""
		(layer "F.Cu")
		(at 15.288006 -104.73563 90)
		(property "Reference" "R3651"
			(at 0 0 90)
			(layer "F.SilkS")
			(hide yes)
			(effects
				(font
					(size 1.27 1.27)
				)
			)
		)
		(property "Value" ""
			(at 0 0 90)
			(layer "F.Fab")
			(effects
				(font
					(size 1.27 1.27)
				)
			)
		)
		(duplicate_pad_numbers_are_jumpers no)
		(fp_line
			(start 0.7874 -0.4064)
			(end 0.7874 0.4064)
			(stroke
				(width 0.1524)
				(type default)
			)
			(layer "F.SilkS")
		)
		(fp_line
			(start -0.7874 -0.4064)
			(end 0.00635 -0.4064)
			(stroke
				(width 0.1524)
				(type default)
			)
			(layer "F.SilkS")
		)
		(fp_line
			(start -0.01397 0.4064)
			(end -0.7874 0.4064)
			(stroke
				(width 0.1524)
				(type default)
			)
			(layer "F.SilkS")
		)
		(fp_line
			(start -0.12065 -0.305054)
			(end -0.12065 -0.2794)
			(stroke
				(width 0.1)
				(type default)
			)
			(layer "F.Fab")
		)
		(fp_line
			(start -0.67945 -0.305054)
			(end -0.12065 -0.305054)
			(stroke
				(width 0.1)
				(type default)
			)
			(layer "F.Fab")
		)
		(fp_line
			(start 0.67945 -0.3048)
			(end 0.67945 0.3048)
			(stroke
				(width 0.1)
				(type default)
			)
			(layer "F.Fab")
		)
		(fp_line
			(start 0.12065 -0.3048)
			(end 0.67945 -0.3048)
			(stroke
				(width 0.1)
				(type default)
			)
			(layer "F.Fab")
		)
		(fp_line
			(start 0.12065 -0.2794)
			(end 0.12065 -0.3048)
			(stroke
				(width 0.1)
				(type default)
			)
			(layer "F.Fab")
		)
		(fp_line
			(start -0.12065 -0.2794)
			(end 0.12065 -0.2794)
			(stroke
				(width 0.1)
				(type default)
			)
			(layer "F.Fab")
		)
		(fp_line
			(start 0.120396 0.2794)
			(end -0.12065 0.2794)
			(stroke
				(width 0.1)
				(type default)
			)
			(layer "F.Fab")
		)
		(fp_line
			(start -0.12065 0.2794)
			(end -0.12065 0.3048)
			(stroke
				(width 0.1)
				(type default)
			)
			(layer "F.Fab")
		)
		(fp_line
			(start 0.67945 0.3048)
			(end 0.120396 0.3048)
			(stroke
				(width 0.1)
				(type default)
			)
			(layer "F.Fab")
		)
		(fp_line
			(start 0.120396 0.3048)
			(end 0.120396 0.2794)
			(stroke
				(width 0.1)
				(type default)
			)
			(layer "F.Fab")
		)
		(fp_line
			(start -0.12065 0.3048)
			(end -0.67945 0.3048)
			(stroke
				(width 0.1)
				(type default)
			)
			(layer "F.Fab")
		)
		(fp_line
			(start -0.67945 0.3048)
			(end -0.67945 -0.305054)
			(stroke
				(width 0.1)
				(type default)
			)
			(layer "F.Fab")
		)
		(pad "1" smd rect
			(at -0.40005 0 270)
			(size 0.4572 0.508)
			(layers "F.Cu" "F.Mask" "F.Paste")
			(net "USB2_P0_R_DP")
		)
		(pad "2" smd rect
			(at 0.40005 0 270)
			(size 0.4572 0.508)
			(layers "F.Cu" "F.Mask" "F.Paste")
			(net "USB2_HOST_BMC_B_DP")
		)
	)
	(footprint ""
		(layer "F.Cu")
		(at 303.9872 -22.606 180)
		(property "Reference" "R4791"
			(at 0 0 180)
			(layer "F.SilkS")
			(hide yes)
			(effects
				(font
					(size 1.27 1.27)
				)
			)
		)
		(property "Value" ""
			(at 0 0 180)
			(layer "F.Fab")
			(effects
				(font
					(size 1.27 1.27)
				)
			)
		)
		(duplicate_pad_numbers_are_jumpers no)
		(fp_line
			(start 0.7874 0.4064)
			(end -0.7874 0.4064)
			(stroke
				(width 0.1524)
				(type default)
			)
			(layer "F.SilkS")
		)
		(fp_line
			(start 0.7874 -0.4064)
			(end 0.7874 0.4064)
			(stroke
				(width 0.1524)
				(type default)
			)
			(layer "F.SilkS")
		)
		(fp_line
			(start -0.7874 0.4064)
			(end -0.7874 -0.4064)
			(stroke
				(width 0.1524)
				(type default)
			)
			(layer "F.SilkS")
		)
		(fp_line
			(start -0.7874 -0.4064)
			(end 0.7874 -0.4064)
			(stroke
				(width 0.1524)
				(type default)
			)
			(layer "F.SilkS")
		)
		(fp_line
			(start 0.67945 0.3048)
			(end 0.120396 0.3048)
			(stroke
				(width 0.1)
				(type default)
			)
			(layer "F.Fab")
		)
		(fp_line
			(start 0.67945 -0.3048)
			(end 0.67945 0.3048)
			(stroke
				(width 0.1)
				(type default)
			)
			(layer "F.Fab")
		)
		(fp_line
			(start 0.12065 -0.2794)
			(end 0.12065 -0.3048)
			(stroke
				(width 0.1)
				(type default)
			)
			(layer "F.Fab")
		)
		(fp_line
			(start 0.12065 -0.3048)
			(end 0.67945 -0.3048)
			(stroke
				(width 0.1)
				(type default)
			)
			(layer "F.Fab")
		)
		(fp_line
			(start 0.120396 0.3048)
			(end 0.120396 0.2794)
			(stroke
				(width 0.1)
				(type default)
			)
			(layer "F.Fab")
		)
		(fp_line
			(start 0.120396 0.2794)
			(end -0.12065 0.2794)
			(stroke
				(width 0.1)
				(type default)
			)
			(layer "F.Fab")
		)
		(fp_line
			(start -0.12065 0.3048)
			(end -0.67945 0.3048)
			(stroke
				(width 0.1)
				(type default)
			)
			(layer "F.Fab")
		)
		(fp_line
			(start -0.12065 0.2794)
			(end -0.12065 0.3048)
			(stroke
				(width 0.1)
				(type default)
			)
			(layer "F.Fab")
		)
		(fp_line
			(start -0.12065 -0.2794)
			(end 0.12065 -0.2794)
			(stroke
				(width 0.1)
				(type default)
			)
			(layer "F.Fab")
		)
		(fp_line
			(start -0.12065 -0.305054)
			(end -0.12065 -0.2794)
			(stroke
				(width 0.1)
				(type default)
			)
			(layer "F.Fab")
		)
		(fp_line
			(start -0.67945 0.3048)
			(end -0.67945 -0.305054)
			(stroke
				(width 0.1)
				(type default)
			)
			(layer "F.Fab")
		)
		(fp_line
			(start -0.67945 -0.305054)
			(end -0.12065 -0.305054)
			(stroke
				(width 0.1)
				(type default)
			)
			(layer "F.Fab")
		)
		(pad "1" smd circle
			(at -0.40005 0 180)
			(size 0 0)
			(layers "F.Cu" "F.Mask" "F.Paste")
			(net "PWRGD_DSW_PWROK_TRIGGER")
		)
		(pad "2" smd circle
			(at 0.40005 0 180)
			(size 0 0)
			(layers "F.Cu" "F.Mask" "F.Paste")
			(net "GND")
		)
	)
	(footprint ""
		(layer "F.Cu")
		(at 255.37033 -54.844442 90)
		(property "Reference" "PR3951"
			(at 0 0 90)
			(layer "F.SilkS")
			(hide yes)
			(effects
				(font
					(size 1.27 1.27)
				)
			)
		)
		(property "Value" ""
			(at 0 0 90)
			(layer "F.Fab")
			(effects
				(font
					(size 1.27 1.27)
				)
			)
		)
		(duplicate_pad_numbers_are_jumpers no)
		(fp_line
			(start 0.7874 -0.4064)
			(end 0.7874 0.4064)
			(stroke
				(width 0.1524)
				(type default)
			)
			(layer "F.SilkS")
		)
		(fp_line
			(start -0.7874 -0.4064)
			(end 0.7874 -0.4064)
			(stroke
				(width 0.1524)
				(type default)
			)
			(layer "F.SilkS")
		)
		(fp_line
			(start 0.7874 0.4064)
			(end -0.7874 0.4064)
			(stroke
				(width 0.1524)
				(type default)
			)
			(layer "F.SilkS")
		)
		(fp_line
			(start -0.7874 0.4064)
			(end -0.7874 -0.4064)
			(stroke
				(width 0.1524)
				(type default)
			)
			(layer "F.SilkS")
		)
		(fp_line
			(start -0.12065 -0.305054)
			(end -0.12065 -0.2794)
			(stroke
				(width 0.1)
				(type default)
			)
			(layer "F.Fab")
		)
		(fp_line
			(start -0.67945 -0.305054)
			(end -0.12065 -0.305054)
			(stroke
				(width 0.1)
				(type default)
			)
			(layer "F.Fab")
		)
		(fp_line
			(start 0.67945 -0.3048)
			(end 0.67945 0.3048)
			(stroke
				(width 0.1)
				(type default)
			)
			(layer "F.Fab")
		)
		(fp_line
			(start 0.12065 -0.3048)
			(end 0.67945 -0.3048)
			(stroke
				(width 0.1)
				(type default)
			)
			(layer "F.Fab")
		)
		(fp_line
			(start 0.12065 -0.2794)
			(end 0.12065 -0.3048)
			(stroke
				(width 0.1)
				(type default)
			)
			(layer "F.Fab")
		)
		(fp_line
			(start -0.12065 -0.2794)
			(end 0.12065 -0.2794)
			(stroke
				(width 0.1)
				(type default)
			)
			(layer "F.Fab")
		)
		(fp_line
			(start 0.120396 0.2794)
			(end -0.12065 0.2794)
			(stroke
				(width 0.1)
				(type default)
			)
			(layer "F.Fab")
		)
		(fp_line
			(start -0.12065 0.2794)
			(end -0.12065 0.3048)
			(stroke
				(width 0.1)
				(type default)
			)
			(layer "F.Fab")
		)
		(fp_line
			(start 0.67945 0.3048)
			(end 0.120396 0.3048)
			(stroke
				(width 0.1)
				(type default)
			)
			(layer "F.Fab")
		)
		(fp_line
			(start 0.120396 0.3048)
			(end 0.120396 0.2794)
			(stroke
				(width 0.1)
				(type default)
			)
			(layer "F.Fab")
		)
		(fp_line
			(start -0.12065 0.3048)
			(end -0.67945 0.3048)
			(stroke
				(width 0.1)
				(type default)
			)
			(layer "F.Fab")
		)
		(fp_line
			(start -0.67945 0.3048)
			(end -0.67945 -0.305054)
			(stroke
				(width 0.1)
				(type default)
			)
			(layer "F.Fab")
		)
		(pad "1" smd circle
			(at -0.40005 0 90)
			(size 0 0)
			(layers "F.Cu" "F.Mask" "F.Paste")
			(net "P12V_E1S_FLTB_0")
		)
		(pad "2" smd circle
			(at 0.40005 0 90)
			(size 0 0)
			(layers "F.Cu" "F.Mask" "F.Paste")
			(net "P3V3_AUX")
		)
	)
	(footprint ""
		(layer "F.Cu")
		(at 226.733608 -404.823422)
		(property "Reference" "PC2224"
			(at 0 0 0)
			(layer "F.SilkS")
			(hide yes)
			(effects
				(font
					(size 1.27 1.27)
				)
			)
		)
		(property "Value" ""
			(at 0 0 0)
			(layer "F.Fab")
			(effects
				(font
					(size 1.27 1.27)
				)
			)
		)
		(duplicate_pad_numbers_are_jumpers no)
		(fp_line
			(start -0.7874 -0.4064)
			(end 0.7874 -0.4064)
			(stroke
				(width 0.1524)
				(type default)
			)
			(layer "F.SilkS")
		)
		(fp_line
			(start -0.7874 0.4064)
			(end -0.7874 -0.4064)
			(stroke
				(width 0.1524)
				(type default)
			)
			(layer "F.SilkS")
		)
		(fp_line
			(start 0.7874 -0.4064)
			(end 0.7874 0.4064)
			(stroke
				(width 0.1524)
				(type default)
			)
			(layer "F.SilkS")
		)
		(fp_line
			(start 0.7874 0.4064)
			(end -0.7874 0.4064)
			(stroke
				(width 0.1524)
				(type default)
			)
			(layer "F.SilkS")
		)
		(fp_line
			(start -0.67945 -0.305054)
			(end -0.12065 -0.305054)
			(stroke
				(width 0.1)
				(type default)
			)
			(layer "F.Fab")
		)
		(fp_line
			(start -0.67945 0.3048)
			(end -0.67945 -0.305054)
			(stroke
				(width 0.1)
				(type default)
			)
			(layer "F.Fab")
		)
		(fp_line
			(start -0.12065 -0.305054)
			(end -0.12065 -0.2794)
			(stroke
				(width 0.1)
				(type default)
			)
			(layer "F.Fab")
		)
		(fp_line
			(start -0.12065 -0.2794)
			(end 0.12065 -0.2794)
			(stroke
				(width 0.1)
				(type default)
			)
			(layer "F.Fab")
		)
		(fp_line
			(start -0.12065 0.2794)
			(end -0.12065 0.3048)
			(stroke
				(width 0.1)
				(type default)
			)
			(layer "F.Fab")
		)
		(fp_line
			(start -0.12065 0.3048)
			(end -0.67945 0.3048)
			(stroke
				(width 0.1)
				(type default)
			)
			(layer "F.Fab")
		)
		(fp_line
			(start 0.120396 0.2794)
			(end -0.12065 0.2794)
			(stroke
				(width 0.1)
				(type default)
			)
			(layer "F.Fab")
		)
		(fp_line
			(start 0.120396 0.3048)
			(end 0.120396 0.2794)
			(stroke
				(width 0.1)
				(type default)
			)
			(layer "F.Fab")
		)
		(fp_line
			(start 0.12065 -0.3048)
			(end 0.67945 -0.3048)
			(stroke
				(width 0.1)
				(type default)
			)
			(layer "F.Fab")
		)
		(fp_line
			(start 0.12065 -0.2794)
			(end 0.12065 -0.3048)
			(stroke
				(width 0.1)
				(type default)
			)
			(layer "F.Fab")
		)
		(fp_line
			(start 0.67945 -0.3048)
			(end 0.67945 0.3048)
			(stroke
				(width 0.1)
				(type default)
			)
			(layer "F.Fab")
		)
		(fp_line
			(start 0.67945 0.3048)
			(end 0.120396 0.3048)
			(stroke
				(width 0.1)
				(type default)
			)
			(layer "F.Fab")
		)
		(pad "1" smd circle
			(at -0.40005 0)
			(size 0 0)
			(layers "F.Cu" "F.Mask" "F.Paste")
			(net "HSC_ON")
		)
		(pad "2" smd circle
			(at 0.40005 0)
			(size 0 0)
			(layers "F.Cu" "F.Mask" "F.Paste")
			(net "AGND_HSC")
		)
	)
)
